(kicad_pcb
	(version 20260206)
	(generator "pcbnew")
	(generator_version "10.0")
	(general
		(thickness 1.6)
		(legacy_teardrops no)
	)
	(paper "A4")
	(title_block
		(title "01162023_DA0F0TEBIF0_F0T_Expander_BD_F_brd_V02_OCP.brd")
		(comment 1 "Grand Teton / footprints 249-254 of 9728")
	)
	(layers
		(0 "F.Cu" signal "TOP")
		(4 "In1.Cu" signal "GND")
		(6 "In2.Cu" signal "VCC")
		(8 "In3.Cu" signal "VCC1")
		(10 "In4.Cu" signal "GND1")
		(12 "In5.Cu" signal "IN1")
		(14 "In6.Cu" signal "GND2")
		(16 "In7.Cu" signal "IN2")
		(18 "In8.Cu" signal "GND3")
		(20 "In9.Cu" signal "IN3")
		(22 "In10.Cu" signal "GND4")
		(24 "In11.Cu" signal "IN4")
		(26 "In12.Cu" signal "GND5")
		(28 "In13.Cu" signal "IN5")
		(30 "In14.Cu" signal "GND6")
		(32 "In15.Cu" signal "IN6")
		(34 "In16.Cu" signal "GND7")
		(2 "B.Cu" signal "BOTTOM")
		(9 "F.Adhes" user "F.Adhesive")
		(11 "B.Adhes" user "B.Adhesive")
		(13 "F.Paste" user "Package Geometry/Pastemask Top")
		(15 "B.Paste" user "Package Geometry/Pastemask Bottom")
		(5 "F.SilkS" user "Ref Des/Silkscreen Top")
		(7 "B.SilkS" user "Ref Des/Silkscreen Bottom")
		(1 "F.Mask" user "Board Geometry/Soldermask Top")
		(3 "B.Mask" user "Board Geometry/Soldermask Bottom")
		(17 "Dwgs.User" user "User.Drawings")
		(19 "Cmts.User" user "User.Comments")
		(21 "Eco1.User" user "User.Eco1")
		(23 "Eco2.User" user "User.Eco2")
		(25 "Edge.Cuts" user "Board Geometry/Outline")
		(27 "Margin" user)
		(31 "F.CrtYd" user "Package Geometry/Place Bound Top")
		(29 "B.CrtYd" user "Package Geometry/Place Bound Bottom")
		(35 "F.Fab" user "Ref Des/Assembly Top")
		(33 "B.Fab" user "Ref Des/Assembly Bottom")
	)
	(footprint ""
		(layer "F.Cu")
		(at 77.569568 -5.564632)
		(property "Reference" "U416"
			(at -1.471168 3.229102 0)
			(unlocked yes)
			(layer "F.SilkS")
			(effects
				(font
					(size 0.7874 0.5842)
					(thickness 0.1524)
				)
				(justify left)
			)
		)
		(property "Value" ""
			(at 0 0 0)
			(layer "F.Fab")
			(effects
				(font
					(size 1.27 1.27)
				)
			)
		)
		(duplicate_pad_numbers_are_jumpers no)
		(fp_line
			(start -3.447796 -2.500122)
			(end -3.447796 2.500122)
			(stroke
				(width 0.1524)
				(type default)
			)
			(layer "F.SilkS")
		)
		(fp_line
			(start -3.447796 2.500122)
			(end 3.447796 2.500122)
			(stroke
				(width 0.1524)
				(type default)
			)
			(layer "F.SilkS")
		)
		(fp_line
			(start -1.484122 -2.500122)
			(end -3.447796 -2.500122)
			(stroke
				(width 0.1524)
				(type default)
			)
			(layer "F.SilkS")
		)
		(fp_line
			(start 0 -1.016)
			(end -1.484122 -2.500122)
			(stroke
				(width 0.1524)
				(type default)
			)
			(layer "F.SilkS")
		)
		(fp_line
			(start 1.484122 -2.500122)
			(end 0 -1.016)
			(stroke
				(width 0.1524)
				(type default)
			)
			(layer "F.SilkS")
		)
		(fp_line
			(start 3.447796 -2.500122)
			(end 1.484122 -2.500122)
			(stroke
				(width 0.1524)
				(type default)
			)
			(layer "F.SilkS")
		)
		(fp_line
			(start 3.447796 2.500122)
			(end 3.447796 -2.500122)
			(stroke
				(width 0.1524)
				(type default)
			)
			(layer "F.SilkS")
		)
		(fp_poly
			(pts
				(xy -3.910838 -3.106928) (xy -4.62915 -2.388616) (xy -3.551682 -2.02946)
			)
			(stroke
				(width 0)
				(type default)
			)
			(fill yes)
			(layer "F.SilkS")
		)
		(fp_line
			(start -1.999996 -2.500122)
			(end -1.999996 2.500122)
			(stroke
				(width 0.1)
				(type default)
			)
			(layer "F.Fab")
		)
		(fp_line
			(start -1.999996 2.500122)
			(end 1.999996 2.500122)
			(stroke
				(width 0.1)
				(type default)
			)
			(layer "F.Fab")
		)
		(fp_line
			(start 1.999996 -2.500122)
			(end -1.999996 -2.500122)
			(stroke
				(width 0.1)
				(type default)
			)
			(layer "F.Fab")
		)
		(fp_line
			(start 1.999996 2.500122)
			(end 1.999996 -2.500122)
			(stroke
				(width 0.1)
				(type default)
			)
			(layer "F.Fab")
		)
		(fp_poly
			(pts
				(xy -4.5974 -2.413) (xy -4.5974 -1.397) (xy -3.5814 -1.905)
			)
			(stroke
				(width 0)
				(type default)
			)
			(fill yes)
			(layer "F.Fab")
		)
		(pad "1" smd rect
			(at -2.649982 -1.905 270)
			(size 0.6096 1.3208)
			(layers "F.Cu" "F.Mask" "F.Paste")
			(net "SMB_LM75_2_SDA")
		)
		(pad "2" smd rect
			(at -2.649982 -0.635 270)
			(size 0.6096 1.3208)
			(layers "F.Cu" "F.Mask" "F.Paste")
			(net "SMB_LM75_2_SCL")
		)
		(pad "3" smd rect
			(at -2.649982 0.635 270)
			(size 0.6096 1.3208)
			(layers "F.Cu" "F.Mask" "F.Paste")
			(net "Net_408")
		)
		(pad "4" smd rect
			(at -2.649982 1.905 270)
			(size 0.6096 1.3208)
			(layers "F.Cu" "F.Mask" "F.Paste")
			(net "GND")
		)
		(pad "5" smd rect
			(at 2.649982 1.905 270)
			(size 0.6096 1.3208)
			(layers "F.Cu" "F.Mask" "F.Paste")
			(net "LM75_2_A2")
		)
		(pad "6" smd rect
			(at 2.649982 0.635 270)
			(size 0.6096 1.3208)
			(layers "F.Cu" "F.Mask" "F.Paste")
			(net "LM75_2_A1")
		)
		(pad "7" smd rect
			(at 2.649982 -0.635 270)
			(size 0.6096 1.3208)
			(layers "F.Cu" "F.Mask" "F.Paste")
			(net "LM75_2_A0")
		)
		(pad "8" smd rect
			(at 2.649982 -1.905 270)
			(size 0.6096 1.3208)
			(layers "F.Cu" "F.Mask" "F.Paste")
			(net "P3V3_AUX")
		)
	)
	(footprint ""
		(layer "F.Cu")
		(at 20.434554 -30.94609 180)
		(property "Reference" "C69"
			(at 0 0 180)
			(layer "F.SilkS")
			(hide yes)
			(effects
				(font
					(size 1.27 1.27)
				)
			)
		)
		(property "Value" ""
			(at 0 0 180)
			(layer "F.Fab")
			(effects
				(font
					(size 1.27 1.27)
				)
			)
		)
		(duplicate_pad_numbers_are_jumpers no)
		(fp_line
			(start 0.299974 0.150114)
			(end -0.299974 0.150114)
			(stroke
				(width 0.1)
				(type default)
			)
			(layer "F.Fab")
		)
		(fp_line
			(start 0.299974 -0.150114)
			(end 0.299974 0.150114)
			(stroke
				(width 0.1)
				(type default)
			)
			(layer "F.Fab")
		)
		(fp_line
			(start -0.299974 0.150114)
			(end -0.299974 -0.150114)
			(stroke
				(width 0.1)
				(type default)
			)
			(layer "F.Fab")
		)
		(fp_line
			(start -0.299974 -0.150114)
			(end 0.299974 -0.150114)
			(stroke
				(width 0.1)
				(type default)
			)
			(layer "F.Fab")
		)
		(pad "1" smd rect
			(at -0.2667 0 180)
			(size 0.3048 0.381)
			(layers "F.Cu" "F.Mask" "F.Paste")
			(net "P5E_PEX0_STN2_TX_DP<45>")
		)
		(pad "2" smd rect
			(at 0.2667 0 180)
			(size 0.3048 0.381)
			(layers "F.Cu" "F.Mask" "F.Paste")
			(net "P5E_PEX0_STN2_TX_C_DP<45>")
		)
	)
	(footprint ""
		(layer "F.Cu")
		(at 320.019934 -289.230816 -90)
		(property "Reference" "R3979"
			(at 0 0 270)
			(layer "F.SilkS")
			(hide yes)
			(effects
				(font
					(size 1.27 1.27)
				)
			)
		)
		(property "Value" ""
			(at 0 0 270)
			(layer "F.Fab")
			(effects
				(font
					(size 1.27 1.27)
				)
			)
		)
		(duplicate_pad_numbers_are_jumpers no)
		(fp_line
			(start -0.7874 0.4064)
			(end -0.7874 -0.4064)
			(stroke
				(width 0.1524)
				(type default)
			)
			(layer "F.SilkS")
		)
		(fp_line
			(start 0.7874 0.4064)
			(end -0.7874 0.4064)
			(stroke
				(width 0.1524)
				(type default)
			)
			(layer "F.SilkS")
		)
		(fp_line
			(start -0.7874 -0.4064)
			(end 0.7874 -0.4064)
			(stroke
				(width 0.1524)
				(type default)
			)
			(layer "F.SilkS")
		)
		(fp_line
			(start 0.7874 -0.4064)
			(end 0.7874 0.4064)
			(stroke
				(width 0.1524)
				(type default)
			)
			(layer "F.SilkS")
		)
		(fp_line
			(start -0.67945 0.3048)
			(end -0.67945 -0.305054)
			(stroke
				(width 0.1)
				(type default)
			)
			(layer "F.Fab")
		)
		(fp_line
			(start -0.12065 0.3048)
			(end -0.67945 0.3048)
			(stroke
				(width 0.1)
				(type default)
			)
			(layer "F.Fab")
		)
		(fp_line
			(start 0.120396 0.3048)
			(end 0.120396 0.2794)
			(stroke
				(width 0.1)
				(type default)
			)
			(layer "F.Fab")
		)
		(fp_line
			(start 0.67945 0.3048)
			(end 0.120396 0.3048)
			(stroke
				(width 0.1)
				(type default)
			)
			(layer "F.Fab")
		)
		(fp_line
			(start -0.12065 0.2794)
			(end -0.12065 0.3048)
			(stroke
				(width 0.1)
				(type default)
			)
			(layer "F.Fab")
		)
		(fp_line
			(start 0.120396 0.2794)
			(end -0.12065 0.2794)
			(stroke
				(width 0.1)
				(type default)
			)
			(layer "F.Fab")
		)
		(fp_line
			(start -0.12065 -0.2794)
			(end 0.12065 -0.2794)
			(stroke
				(width 0.1)
				(type default)
			)
			(layer "F.Fab")
		)
		(fp_line
			(start 0.12065 -0.2794)
			(end 0.12065 -0.3048)
			(stroke
				(width 0.1)
				(type default)
			)
			(layer "F.Fab")
		)
		(fp_line
			(start 0.12065 -0.3048)
			(end 0.67945 -0.3048)
			(stroke
				(width 0.1)
				(type default)
			)
			(layer "F.Fab")
		)
		(fp_line
			(start 0.67945 -0.3048)
			(end 0.67945 0.3048)
			(stroke
				(width 0.1)
				(type default)
			)
			(layer "F.Fab")
		)
		(fp_line
			(start -0.67945 -0.305054)
			(end -0.12065 -0.305054)
			(stroke
				(width 0.1)
				(type default)
			)
			(layer "F.Fab")
		)
		(fp_line
			(start -0.12065 -0.305054)
			(end -0.12065 -0.2794)
			(stroke
				(width 0.1)
				(type default)
			)
			(layer "F.Fab")
		)
		(pad "1" smd circle
			(at -0.40005 0 270)
			(size 0 0)
			(layers "F.Cu" "F.Mask" "F.Paste")
			(net "SMB_PEX2_HOST_LS_SDA")
		)
		(pad "2" smd circle
			(at 0.40005 0 270)
			(size 0 0)
			(layers "F.Cu" "F.Mask" "F.Paste")
			(net "P3V3_AUX")
		)
	)
	(footprint ""
		(layer "F.Cu")
		(at 123.71324 -136.328404 180)
		(property "Reference" "PC325"
			(at 0 0 180)
			(layer "F.SilkS")
			(hide yes)
			(effects
				(font
					(size 1.27 1.27)
				)
			)
		)
		(property "Value" ""
			(at 0 0 180)
			(layer "F.Fab")
			(effects
				(font
					(size 1.27 1.27)
				)
			)
		)
		(duplicate_pad_numbers_are_jumpers no)
		(fp_line
			(start 0.7874 0.4064)
			(end -0.7874 0.4064)
			(stroke
				(width 0.1524)
				(type default)
			)
			(layer "F.SilkS")
		)
		(fp_line
			(start 0.7874 -0.4064)
			(end 0.7874 0.4064)
			(stroke
				(width 0.1524)
				(type default)
			)
			(layer "F.SilkS")
		)
		(fp_line
			(start -0.7874 0.4064)
			(end -0.7874 -0.4064)
			(stroke
				(width 0.1524)
				(type default)
			)
			(layer "F.SilkS")
		)
		(fp_line
			(start -0.7874 -0.4064)
			(end 0.7874 -0.4064)
			(stroke
				(width 0.1524)
				(type default)
			)
			(layer "F.SilkS")
		)
		(fp_line
			(start 0.67945 0.3048)
			(end 0.120396 0.3048)
			(stroke
				(width 0.1)
				(type default)
			)
			(layer "F.Fab")
		)
		(fp_line
			(start 0.67945 -0.3048)
			(end 0.67945 0.3048)
			(stroke
				(width 0.1)
				(type default)
			)
			(layer "F.Fab")
		)
		(fp_line
			(start 0.12065 -0.2794)
			(end 0.12065 -0.3048)
			(stroke
				(width 0.1)
				(type default)
			)
			(layer "F.Fab")
		)
		(fp_line
			(start 0.12065 -0.3048)
			(end 0.67945 -0.3048)
			(stroke
				(width 0.1)
				(type default)
			)
			(layer "F.Fab")
		)
		(fp_line
			(start 0.120396 0.3048)
			(end 0.120396 0.2794)
			(stroke
				(width 0.1)
				(type default)
			)
			(layer "F.Fab")
		)
		(fp_line
			(start 0.120396 0.2794)
			(end -0.12065 0.2794)
			(stroke
				(width 0.1)
				(type default)
			)
			(layer "F.Fab")
		)
		(fp_line
			(start -0.12065 0.3048)
			(end -0.67945 0.3048)
			(stroke
				(width 0.1)
				(type default)
			)
			(layer "F.Fab")
		)
		(fp_line
			(start -0.12065 0.2794)
			(end -0.12065 0.3048)
			(stroke
				(width 0.1)
				(type default)
			)
			(layer "F.Fab")
		)
		(fp_line
			(start -0.12065 -0.2794)
			(end 0.12065 -0.2794)
			(stroke
				(width 0.1)
				(type default)
			)
			(layer "F.Fab")
		)
		(fp_line
			(start -0.12065 -0.305054)
			(end -0.12065 -0.2794)
			(stroke
				(width 0.1)
				(type default)
			)
			(layer "F.Fab")
		)
		(fp_line
			(start -0.67945 0.3048)
			(end -0.67945 -0.305054)
			(stroke
				(width 0.1)
				(type default)
			)
			(layer "F.Fab")
		)
		(fp_line
			(start -0.67945 -0.305054)
			(end -0.12065 -0.305054)
			(stroke
				(width 0.1)
				(type default)
			)
			(layer "F.Fab")
		)
		(pad "1" smd circle
			(at -0.40005 0 180)
			(size 0 0)
			(layers "F.Cu" "F.Mask" "F.Paste")
			(net "P5V_AUX")
		)
		(pad "2" smd circle
			(at 0.40005 0 180)
			(size 0 0)
			(layers "F.Cu" "F.Mask" "F.Paste")
			(net "GND")
		)
	)
	(footprint ""
		(layer "F.Cu")
		(at 121.441972 -121.103136)
		(property "Reference" "PC596"
			(at 0 0 0)
			(layer "F.SilkS")
			(hide yes)
			(effects
				(font
					(size 1.27 1.27)
				)
			)
		)
		(property "Value" ""
			(at 0 0 0)
			(layer "F.Fab")
			(effects
				(font
					(size 1.27 1.27)
				)
			)
		)
		(duplicate_pad_numbers_are_jumpers no)
		(fp_line
			(start -0.7874 -0.4064)
			(end 0.7874 -0.4064)
			(stroke
				(width 0.1524)
				(type default)
			)
			(layer "F.SilkS")
		)
		(fp_line
			(start -0.7874 0.4064)
			(end -0.7874 -0.4064)
			(stroke
				(width 0.1524)
				(type default)
			)
			(layer "F.SilkS")
		)
		(fp_line
			(start 0.7874 -0.4064)
			(end 0.7874 0.4064)
			(stroke
				(width 0.1524)
				(type default)
			)
			(layer "F.SilkS")
		)
		(fp_line
			(start 0.7874 0.4064)
			(end -0.7874 0.4064)
			(stroke
				(width 0.1524)
				(type default)
			)
			(layer "F.SilkS")
		)
		(fp_line
			(start -0.67945 -0.305054)
			(end -0.12065 -0.305054)
			(stroke
				(width 0.1)
				(type default)
			)
			(layer "F.Fab")
		)
		(fp_line
			(start -0.67945 0.3048)
			(end -0.67945 -0.305054)
			(stroke
				(width 0.1)
				(type default)
			)
			(layer "F.Fab")
		)
		(fp_line
			(start -0.12065 -0.305054)
			(end -0.12065 -0.2794)
			(stroke
				(width 0.1)
				(type default)
			)
			(layer "F.Fab")
		)
		(fp_line
			(start -0.12065 -0.2794)
			(end 0.12065 -0.2794)
			(stroke
				(width 0.1)
				(type default)
			)
			(layer "F.Fab")
		)
		(fp_line
			(start -0.12065 0.2794)
			(end -0.12065 0.3048)
			(stroke
				(width 0.1)
				(type default)
			)
			(layer "F.Fab")
		)
		(fp_line
			(start -0.12065 0.3048)
			(end -0.67945 0.3048)
			(stroke
				(width 0.1)
				(type default)
			)
			(layer "F.Fab")
		)
		(fp_line
			(start 0.120396 0.2794)
			(end -0.12065 0.2794)
			(stroke
				(width 0.1)
				(type default)
			)
			(layer "F.Fab")
		)
		(fp_line
			(start 0.120396 0.3048)
			(end 0.120396 0.2794)
			(stroke
				(width 0.1)
				(type default)
			)
			(layer "F.Fab")
		)
		(fp_line
			(start 0.12065 -0.3048)
			(end 0.67945 -0.3048)
			(stroke
				(width 0.1)
				(type default)
			)
			(layer "F.Fab")
		)
		(fp_line
			(start 0.12065 -0.2794)
			(end 0.12065 -0.3048)
			(stroke
				(width 0.1)
				(type default)
			)
			(layer "F.Fab")
		)
		(fp_line
			(start 0.67945 -0.3048)
			(end 0.67945 0.3048)
			(stroke
				(width 0.1)
				(type default)
			)
			(layer "F.Fab")
		)
		(fp_line
			(start 0.67945 0.3048)
			(end 0.120396 0.3048)
			(stroke
				(width 0.1)
				(type default)
			)
			(layer "F.Fab")
		)
		(pad "1" smd circle
			(at -0.40005 0)
			(size 0 0)
			(layers "F.Cu" "F.Mask" "F.Paste")
			(net "P3V3_CO_MODE")
		)
		(pad "2" smd circle
			(at 0.40005 0)
			(size 0 0)
			(layers "F.Cu" "F.Mask" "F.Paste")
			(net "GND")
		)
	)
	(footprint ""
		(layer "F.Cu")
		(at 306.160932 -37.951156)
		(property "Reference" "Q227"
			(at 2.12344 -1.925574 0)
			(unlocked yes)
			(layer "F.SilkS")
			(effects
				(font
					(size 0.7874 0.5842)
					(thickness 0.1524)
				)
			)
		)
		(property "Value" ""
			(at 0 0 0)
			(layer "F.Fab")
			(effects
				(font
					(size 1.27 1.27)
				)
			)
		)
		(duplicate_pad_numbers_are_jumpers no)
		(fp_line
			(start -1.376172 -1.199896)
			(end -0.508 -1.199896)
			(stroke
				(width 0.1524)
				(type default)
			)
			(layer "F.SilkS")
		)
		(fp_line
			(start -1.376172 1.199896)
			(end -1.376172 -1.199896)
			(stroke
				(width 0.1524)
				(type default)
			)
			(layer "F.SilkS")
		)
		(fp_line
			(start -0.508 -1.199896)
			(end 0 -0.762)
			(stroke
				(width 0.1524)
				(type default)
			)
			(layer "F.SilkS")
		)
		(fp_line
			(start 0 -0.762)
			(end 0.508 -1.199896)
			(stroke
				(width 0.1524)
				(type default)
			)
			(layer "F.SilkS")
		)
		(fp_line
			(start 0.508 -1.199896)
			(end 1.376172 -1.199896)
			(stroke
				(width 0.1524)
				(type default)
			)
			(layer "F.SilkS")
		)
		(fp_line
			(start 1.376172 -1.199896)
			(end 1.376172 1.199896)
			(stroke
				(width 0.1524)
				(type default)
			)
			(layer "F.SilkS")
		)
		(fp_line
			(start 1.376172 1.199896)
			(end -1.376172 1.199896)
			(stroke
				(width 0.1524)
				(type default)
			)
			(layer "F.SilkS")
		)
		(fp_poly
			(pts
				(xy -1.462278 -0.9652) (xy -1.731772 -1.773428) (xy -2.270506 -1.234694)
			)
			(stroke
				(width 0)
				(type default)
			)
			(fill yes)
			(layer "F.SilkS")
		)
		(fp_line
			(start -0.674878 -1.100074)
			(end 0.674878 -1.100074)
			(stroke
				(width 0.1)
				(type default)
			)
			(layer "F.Fab")
		)
		(fp_line
			(start -0.674878 1.100074)
			(end -0.674878 -1.100074)
			(stroke
				(width 0.1)
				(type default)
			)
			(layer "F.Fab")
		)
		(fp_line
			(start 0.674878 -1.100074)
			(end 0.674878 1.100074)
			(stroke
				(width 0.1)
				(type default)
			)
			(layer "F.Fab")
		)
		(fp_line
			(start 0.674878 1.100074)
			(end -0.674878 1.100074)
			(stroke
				(width 0.1)
				(type default)
			)
			(layer "F.Fab")
		)
		(fp_poly
			(pts
				(xy -1.4605 -0.7493) (xy -2.2225 -1.1303) (xy -2.2225 -0.3683)
			)
			(stroke
				(width 0)
				(type default)
			)
			(fill yes)
			(layer "F.Fab")
		)
		(pad "1" smd rect
			(at -0.899922 -0.750062 270)
			(size 0.6096 0.6096)
			(layers "F.Cu" "F.Mask" "F.Paste")
			(net "GND")
		)
		(pad "2" smd rect
			(at -0.899922 0 270)
			(size 0.4064 0.6096)
			(layers "F.Cu" "F.Mask" "F.Paste")
			(net "P3V3_SSD11_PG_G1")
		)
		(pad "3" smd rect
			(at -0.899922 0.750062 270)
			(size 0.6096 0.6096)
			(layers "F.Cu" "F.Mask" "F.Paste")
			(net "PWRGD_P3V3_SSD11_D")
		)
		(pad "4" smd rect
			(at 0.899922 0.750062 270)
			(size 0.6096 0.6096)
			(layers "F.Cu" "F.Mask" "F.Paste")
			(net "GND")
		)
		(pad "5" smd rect
			(at 0.899922 0 270)
			(size 0.4064 0.6096)
			(layers "F.Cu" "F.Mask" "F.Paste")
			(net "P3V3_SSD11_PG_G2")
		)
		(pad "6" smd rect
			(at 0.899922 -0.750062 270)
			(size 0.6096 0.6096)
			(layers "F.Cu" "F.Mask" "F.Paste")
			(net "P3V3_SSD11_PG_G2")
		)
	)
)
